(kicad_pcb
	(version 20260206)
	(generator "pcbnew")
	(generator_version "10.0")
	(general
		(thickness 1.6)
		(legacy_teardrops no)
	)
	(paper "A4")
	(title_block
		(title "9052_F0T_PDB_Converter_Brick_F_V03_1208_1600_OCP.brd")
		(comment 1 "Grand Teton / footprints 336-339 of 578")
	)
	(layers
		(0 "F.Cu" signal "TOP")
		(4 "In1.Cu" signal "GND")
		(6 "In2.Cu" signal "IN1")
		(8 "In3.Cu" signal "GND1")
		(10 "In4.Cu" signal "VCC")
		(12 "In5.Cu" signal "VCC1")
		(14 "In6.Cu" signal "GND2")
		(16 "In7.Cu" signal "IN2")
		(18 "In8.Cu" signal "GND3")
		(2 "B.Cu" signal "BOTTOM")
		(9 "F.Adhes" user "F.Adhesive")
		(11 "B.Adhes" user "B.Adhesive")
		(13 "F.Paste" user "Package Geometry/Pastemask Top")
		(15 "B.Paste" user "Package Geometry/Pastemask Bottom")
		(5 "F.SilkS" user "Ref Des/Silkscreen Top")
		(7 "B.SilkS" user "Ref Des/Silkscreen Bottom")
		(1 "F.Mask" user "Board Geometry/Soldermask Top")
		(3 "B.Mask" user "Board Geometry/Soldermask Bottom")
		(17 "Dwgs.User" user "User.Drawings")
		(19 "Cmts.User" user "User.Comments")
		(21 "Eco1.User" user "User.Eco1")
		(23 "Eco2.User" user "User.Eco2")
		(25 "Edge.Cuts" user "Board Geometry/Outline")
		(27 "Margin" user)
		(31 "F.CrtYd" user "Package Geometry/Place Bound Top")
		(29 "B.CrtYd" user "Package Geometry/Place Bound Bottom")
		(35 "F.Fab" user "Ref Des/Assembly Top")
		(33 "B.Fab" user "Ref Des/Assembly Bottom")
	)
	(footprint ""
		(layer "B.Cu")
		(at 273.558 -46.482 -90)
		(property "Reference" "R158"
			(at 0 0 90)
			(layer "B.SilkS")
			(hide yes)
			(effects
				(font
					(size 1.27 1.27)
				)
				(justify mirror)
			)
		)
		(property "Value" ""
			(at 0 0 90)
			(layer "B.Fab")
			(effects
				(font
					(size 1.27 1.27)
				)
				(justify mirror)
			)
		)
		(duplicate_pad_numbers_are_jumpers no)
		(fp_line
			(start -0.7874 0.4064)
			(end 0.7874 0.4064)
			(stroke
				(width 0.1524)
				(type default)
			)
			(layer "B.SilkS")
		)
		(fp_line
			(start 0.7874 0.4064)
			(end 0.7874 -0.4064)
			(stroke
				(width 0.1524)
				(type default)
			)
			(layer "B.SilkS")
		)
		(fp_line
			(start -0.7874 -0.4064)
			(end -0.7874 0.4064)
			(stroke
				(width 0.1524)
				(type default)
			)
			(layer "B.SilkS")
		)
		(fp_line
			(start 0.7874 -0.4064)
			(end -0.7874 -0.4064)
			(stroke
				(width 0.1524)
				(type default)
			)
			(layer "B.SilkS")
		)
		(fp_line
			(start -0.67945 0.3048)
			(end -0.120396 0.3048)
			(stroke
				(width 0.1)
				(type default)
			)
			(layer "B.Fab")
		)
		(fp_line
			(start -0.120396 0.3048)
			(end -0.120396 0.2794)
			(stroke
				(width 0.1)
				(type default)
			)
			(layer "B.Fab")
		)
		(fp_line
			(start 0.12065 0.3048)
			(end 0.67945 0.3048)
			(stroke
				(width 0.1)
				(type default)
			)
			(layer "B.Fab")
		)
		(fp_line
			(start 0.67945 0.3048)
			(end 0.67945 -0.305054)
			(stroke
				(width 0.1)
				(type default)
			)
			(layer "B.Fab")
		)
		(fp_line
			(start -0.120396 0.2794)
			(end 0.12065 0.2794)
			(stroke
				(width 0.1)
				(type default)
			)
			(layer "B.Fab")
		)
		(fp_line
			(start 0.12065 0.2794)
			(end 0.12065 0.3048)
			(stroke
				(width 0.1)
				(type default)
			)
			(layer "B.Fab")
		)
		(fp_line
			(start -0.12065 -0.2794)
			(end -0.12065 -0.3048)
			(stroke
				(width 0.1)
				(type default)
			)
			(layer "B.Fab")
		)
		(fp_line
			(start 0.12065 -0.2794)
			(end -0.12065 -0.2794)
			(stroke
				(width 0.1)
				(type default)
			)
			(layer "B.Fab")
		)
		(fp_line
			(start -0.67945 -0.3048)
			(end -0.67945 0.3048)
			(stroke
				(width 0.1)
				(type default)
			)
			(layer "B.Fab")
		)
		(fp_line
			(start -0.12065 -0.3048)
			(end -0.67945 -0.3048)
			(stroke
				(width 0.1)
				(type default)
			)
			(layer "B.Fab")
		)
		(fp_line
			(start 0.12065 -0.305054)
			(end 0.12065 -0.2794)
			(stroke
				(width 0.1)
				(type default)
			)
			(layer "B.Fab")
		)
		(fp_line
			(start 0.67945 -0.305054)
			(end 0.12065 -0.305054)
			(stroke
				(width 0.1)
				(type default)
			)
			(layer "B.Fab")
		)
		(pad "1" smd circle
			(at 0.40005 0 90)
			(size 0 0)
			(layers "B.Cu" "B.Mask" "B.Paste")
			(net "P52V_HS1_ADR0")
		)
		(pad "2" smd circle
			(at -0.40005 0 90)
			(size 0 0)
			(layers "B.Cu" "B.Mask" "B.Paste")
			(net "GND_FIELD_SIGNAL")
		)
	)
	(footprint ""
		(layer "B.Cu")
		(at 211.836 -76.073 90)
		(property "Reference" "U4"
			(at -0.6858 -4.71297 270)
			(unlocked yes)
			(layer "B.SilkS")
			(effects
				(font
					(size 0.7874 0.5842)
					(thickness 0.1524)
				)
				(justify left mirror)
			)
		)
		(property "Value" ""
			(at 0 0 90)
			(layer "B.Fab")
			(effects
				(font
					(size 1.27 1.27)
				)
				(justify mirror)
			)
		)
		(duplicate_pad_numbers_are_jumpers no)
		(fp_line
			(start 2.0066 -3.9624)
			(end 0.5842 -3.9624)
			(stroke
				(width 0.1524)
				(type default)
			)
			(layer "B.SilkS")
		)
		(fp_line
			(start 0.5842 -3.9624)
			(end 0 -3.3782)
			(stroke
				(width 0.1524)
				(type default)
			)
			(layer "B.SilkS")
		)
		(fp_line
			(start -0.5842 -3.9624)
			(end -2.0066 -3.9624)
			(stroke
				(width 0.1524)
				(type default)
			)
			(layer "B.SilkS")
		)
		(fp_line
			(start -2.0066 -3.9624)
			(end -2.0066 3.9624)
			(stroke
				(width 0.1524)
				(type default)
			)
			(layer "B.SilkS")
		)
		(fp_line
			(start 0 -3.3782)
			(end -0.5842 -3.9624)
			(stroke
				(width 0.1524)
				(type default)
			)
			(layer "B.SilkS")
		)
		(fp_line
			(start 2.0066 3.9624)
			(end 2.0066 -3.9624)
			(stroke
				(width 0.1524)
				(type default)
			)
			(layer "B.SilkS")
		)
		(fp_line
			(start -2.0066 3.9624)
			(end 2.0066 3.9624)
			(stroke
				(width 0.1524)
				(type default)
			)
			(layer "B.SilkS")
		)
		(fp_poly
			(pts
				(xy 2.159 -4.6736) (xy 2.54 -5.4356) (xy 1.778 -5.4356)
			)
			(stroke
				(width 0)
				(type default)
			)
			(fill yes)
			(layer "B.SilkS")
		)
		(fp_line
			(start 2.2479 -3.974846)
			(end 2.2479 -3.80365)
			(stroke
				(width 0.1)
				(type default)
			)
			(layer "B.Fab")
		)
		(fp_line
			(start -2.2479 -3.974846)
			(end 2.2479 -3.974846)
			(stroke
				(width 0.1)
				(type default)
			)
			(layer "B.Fab")
		)
		(fp_line
			(start 3.724402 -3.80365)
			(end 3.724402 3.80365)
			(stroke
				(width 0.1)
				(type default)
			)
			(layer "B.Fab")
		)
		(fp_line
			(start 2.2479 -3.80365)
			(end 3.724402 -3.80365)
			(stroke
				(width 0.1)
				(type default)
			)
			(layer "B.Fab")
		)
		(fp_line
			(start -2.2479 -3.80365)
			(end -2.2479 -3.974846)
			(stroke
				(width 0.1)
				(type default)
			)
			(layer "B.Fab")
		)
		(fp_line
			(start -3.7211 -3.80365)
			(end -2.2479 -3.80365)
			(stroke
				(width 0.1)
				(type default)
			)
			(layer "B.Fab")
		)
		(fp_line
			(start 3.7211 -3.34645)
			(end 3.7211 -3.80365)
			(stroke
				(width 0.1)
				(type default)
			)
			(layer "B.Fab")
		)
		(fp_line
			(start 3.724402 3.80365)
			(end 2.2479 3.80365)
			(stroke
				(width 0.1)
				(type default)
			)
			(layer "B.Fab")
		)
		(fp_line
			(start 2.2479 3.80365)
			(end 2.2479 3.9624)
			(stroke
				(width 0.1)
				(type default)
			)
			(layer "B.Fab")
		)
		(fp_line
			(start -2.2479 3.80365)
			(end -3.7211 3.80365)
			(stroke
				(width 0.1)
				(type default)
			)
			(layer "B.Fab")
		)
		(fp_line
			(start -3.7211 3.80365)
			(end -3.7211 -3.80365)
			(stroke
				(width 0.1)
				(type default)
			)
			(layer "B.Fab")
		)
		(fp_line
			(start 2.2479 3.9624)
			(end -2.2479 3.9624)
			(stroke
				(width 0.1)
				(type default)
			)
			(layer "B.Fab")
		)
		(fp_line
			(start -2.2479 3.9624)
			(end -2.2479 3.80365)
			(stroke
				(width 0.1)
				(type default)
			)
			(layer "B.Fab")
		)
		(fp_poly
			(pts
				(xy 3.8862 -3.570986) (xy 4.6482 -3.189986) (xy 4.6482 -3.951986)
			)
			(stroke
				(width 0)
				(type default)
			)
			(fill yes)
			(layer "B.Fab")
		)
		(pad "1" smd rect
			(at 2.921 -3.57505)
			(size 0.3556 1.4986)
			(layers "B.Cu" "B.Mask" "B.Paste")
			(net "PU_U4_PIN1")
		)
		(pad "2" smd rect
			(at 2.921 -2.925064)
			(size 0.3556 1.4986)
			(layers "B.Cu" "B.Mask" "B.Paste")
			(net "PCA9555_A1")
		)
		(pad "3" smd rect
			(at 2.921 -2.275078)
			(size 0.3556 1.4986)
			(layers "B.Cu" "B.Mask" "B.Paste")
			(net "PCA9555_A2")
		)
		(pad "4" smd rect
			(at 2.921 -1.625092)
			(size 0.3556 1.4986)
			(layers "B.Cu" "B.Mask" "B.Paste")
			(net "P52V_HS1_FLT")
		)
		(pad "5" smd rect
			(at 2.921 -0.975106)
			(size 0.3556 1.4986)
			(layers "B.Cu" "B.Mask" "B.Paste")
			(net "P12V_BRICK0_ALERT_N")
		)
		(pad "6" smd rect
			(at 2.921 -0.32512)
			(size 0.3556 1.4986)
			(layers "B.Cu" "B.Mask" "B.Paste")
			(net "P12V_BRICK1_ALERT_N")
		)
		(pad "7" smd rect
			(at 2.921 0.32512)
			(size 0.3556 1.4986)
			(layers "B.Cu" "B.Mask" "B.Paste")
			(net "P12V_BRICK2_ALERT_N")
		)
		(pad "8" smd rect
			(at 2.921 0.975106)
			(size 0.3556 1.4986)
			(layers "B.Cu" "B.Mask" "B.Paste")
			(net "P12V_BRICK3_ALERT_N")
		)
		(pad "9" smd rect
			(at 2.921 1.625092)
			(size 0.3556 1.4986)
			(layers "B.Cu" "B.Mask" "B.Paste")
			(net "TP_U4_P05")
		)
		(pad "10" smd rect
			(at 2.921 2.275078)
			(size 0.3556 1.4986)
			(layers "B.Cu" "B.Mask" "B.Paste")
			(net "TP_U4_P06")
		)
		(pad "11" smd rect
			(at 2.921 2.925064)
			(size 0.3556 1.4986)
			(layers "B.Cu" "B.Mask" "B.Paste")
			(net "P12V_HPDB_PWRGD")
		)
		(pad "12" smd rect
			(at 2.921 3.57505)
			(size 0.3556 1.4986)
			(layers "B.Cu" "B.Mask" "B.Paste")
			(net "GND")
		)
		(pad "13" smd rect
			(at -2.921 3.57505)
			(size 0.3556 1.4986)
			(layers "B.Cu" "B.Mask" "B.Paste")
			(net "PWRGD_P3V3_HPDB")
		)
		(pad "14" smd rect
			(at -2.921 2.925064)
			(size 0.3556 1.4986)
			(layers "B.Cu" "B.Mask" "B.Paste")
			(net "PRSNT_HPDB_N")
		)
		(pad "15" smd rect
			(at -2.921 2.275078)
			(size 0.3556 1.4986)
			(layers "B.Cu" "B.Mask" "B.Paste")
			(net "BOARD_ID_0")
		)
		(pad "16" smd rect
			(at -2.921 1.625092)
			(size 0.3556 1.4986)
			(layers "B.Cu" "B.Mask" "B.Paste")
			(net "BOARD_ID_1")
		)
		(pad "17" smd rect
			(at -2.921 0.975106)
			(size 0.3556 1.4986)
			(layers "B.Cu" "B.Mask" "B.Paste")
			(net "BOARD_ID_2")
		)
		(pad "18" smd rect
			(at -2.921 0.32512)
			(size 0.3556 1.4986)
			(layers "B.Cu" "B.Mask" "B.Paste")
			(net "SKU_ID_0")
		)
		(pad "19" smd rect
			(at -2.921 -0.32512)
			(size 0.3556 1.4986)
			(layers "B.Cu" "B.Mask" "B.Paste")
			(net "SKU_ID_1")
		)
		(pad "20" smd rect
			(at -2.921 -0.975106)
			(size 0.3556 1.4986)
			(layers "B.Cu" "B.Mask" "B.Paste")
			(net "SKU_ID_2")
		)
		(pad "21" smd rect
			(at -2.921 -1.625092)
			(size 0.3556 1.4986)
			(layers "B.Cu" "B.Mask" "B.Paste")
			(net "PCA9555_A0")
		)
		(pad "22" smd rect
			(at -2.921 -2.275078)
			(size 0.3556 1.4986)
			(layers "B.Cu" "B.Mask" "B.Paste")
			(net "SMB_VPDB_IOEXP_SCL")
		)
		(pad "23" smd rect
			(at -2.921 -2.925064)
			(size 0.3556 1.4986)
			(layers "B.Cu" "B.Mask" "B.Paste")
			(net "SMB_VPDB_IOEXP_SDA")
		)
		(pad "24" smd rect
			(at -2.921 -3.57505)
			(size 0.3556 1.4986)
			(layers "B.Cu" "B.Mask" "B.Paste")
			(net "P3V3_AUX")
		)
	)
	(footprint ""
		(layer "B.Cu")
		(at 208.153 -82.55 -90)
		(property "Reference" "R22"
			(at 0 0 90)
			(layer "B.SilkS")
			(hide yes)
			(effects
				(font
					(size 1.27 1.27)
				)
				(justify mirror)
			)
		)
		(property "Value" ""
			(at 0 0 90)
			(layer "B.Fab")
			(effects
				(font
					(size 1.27 1.27)
				)
				(justify mirror)
			)
		)
		(duplicate_pad_numbers_are_jumpers no)
		(fp_line
			(start -0.7874 0.4064)
			(end 0.7874 0.4064)
			(stroke
				(width 0.1524)
				(type default)
			)
			(layer "B.SilkS")
		)
		(fp_line
			(start 0.7874 0.4064)
			(end 0.7874 -0.4064)
			(stroke
				(width 0.1524)
				(type default)
			)
			(layer "B.SilkS")
		)
		(fp_line
			(start -0.7874 -0.4064)
			(end -0.7874 0.4064)
			(stroke
				(width 0.1524)
				(type default)
			)
			(layer "B.SilkS")
		)
		(fp_line
			(start 0.7874 -0.4064)
			(end -0.7874 -0.4064)
			(stroke
				(width 0.1524)
				(type default)
			)
			(layer "B.SilkS")
		)
		(fp_line
			(start -0.67945 0.3048)
			(end -0.120396 0.3048)
			(stroke
				(width 0.1)
				(type default)
			)
			(layer "B.Fab")
		)
		(fp_line
			(start -0.120396 0.3048)
			(end -0.120396 0.2794)
			(stroke
				(width 0.1)
				(type default)
			)
			(layer "B.Fab")
		)
		(fp_line
			(start 0.12065 0.3048)
			(end 0.67945 0.3048)
			(stroke
				(width 0.1)
				(type default)
			)
			(layer "B.Fab")
		)
		(fp_line
			(start 0.67945 0.3048)
			(end 0.67945 -0.305054)
			(stroke
				(width 0.1)
				(type default)
			)
			(layer "B.Fab")
		)
		(fp_line
			(start -0.120396 0.2794)
			(end 0.12065 0.2794)
			(stroke
				(width 0.1)
				(type default)
			)
			(layer "B.Fab")
		)
		(fp_line
			(start 0.12065 0.2794)
			(end 0.12065 0.3048)
			(stroke
				(width 0.1)
				(type default)
			)
			(layer "B.Fab")
		)
		(fp_line
			(start -0.12065 -0.2794)
			(end -0.12065 -0.3048)
			(stroke
				(width 0.1)
				(type default)
			)
			(layer "B.Fab")
		)
		(fp_line
			(start 0.12065 -0.2794)
			(end -0.12065 -0.2794)
			(stroke
				(width 0.1)
				(type default)
			)
			(layer "B.Fab")
		)
		(fp_line
			(start -0.67945 -0.3048)
			(end -0.67945 0.3048)
			(stroke
				(width 0.1)
				(type default)
			)
			(layer "B.Fab")
		)
		(fp_line
			(start -0.12065 -0.3048)
			(end -0.67945 -0.3048)
			(stroke
				(width 0.1)
				(type default)
			)
			(layer "B.Fab")
		)
		(fp_line
			(start 0.12065 -0.305054)
			(end 0.12065 -0.2794)
			(stroke
				(width 0.1)
				(type default)
			)
			(layer "B.Fab")
		)
		(fp_line
			(start 0.67945 -0.305054)
			(end 0.12065 -0.305054)
			(stroke
				(width 0.1)
				(type default)
			)
			(layer "B.Fab")
		)
		(pad "1" smd circle
			(at 0.40005 0 90)
			(size 0 0)
			(layers "B.Cu" "B.Mask" "B.Paste")
			(net "PCA9555_A1")
		)
		(pad "2" smd circle
			(at -0.40005 0 90)
			(size 0 0)
			(layers "B.Cu" "B.Mask" "B.Paste")
			(net "GND")
		)
	)
	(footprint ""
		(layer "B.Cu")
		(at 58.928 -76.327 180)
		(property "Reference" "R180"
			(at 0 0 0)
			(layer "B.SilkS")
			(hide yes)
			(effects
				(font
					(size 1.27 1.27)
				)
				(justify mirror)
			)
		)
		(property "Value" ""
			(at 0 0 0)
			(layer "B.Fab")
			(effects
				(font
					(size 1.27 1.27)
				)
				(justify mirror)
			)
		)
		(duplicate_pad_numbers_are_jumpers no)
		(fp_line
			(start 0.7874 0.4064)
			(end 0.7874 -0.4064)
			(stroke
				(width 0.1524)
				(type default)
			)
			(layer "B.SilkS")
		)
		(fp_line
			(start 0.7874 -0.4064)
			(end -0.7874 -0.4064)
			(stroke
				(width 0.1524)
				(type default)
			)
			(layer "B.SilkS")
		)
		(fp_line
			(start -0.7874 0.4064)
			(end 0.7874 0.4064)
			(stroke
				(width 0.1524)
				(type default)
			)
			(layer "B.SilkS")
		)
		(fp_line
			(start -0.7874 -0.4064)
			(end -0.7874 0.4064)
			(stroke
				(width 0.1524)
				(type default)
			)
			(layer "B.SilkS")
		)
		(fp_line
			(start 0.67945 0.3048)
			(end 0.67945 -0.305054)
			(stroke
				(width 0.1)
				(type default)
			)
			(layer "B.Fab")
		)
		(fp_line
			(start 0.67945 -0.305054)
			(end 0.12065 -0.305054)
			(stroke
				(width 0.1)
				(type default)
			)
			(layer "B.Fab")
		)
		(fp_line
			(start 0.12065 0.3048)
			(end 0.67945 0.3048)
			(stroke
				(width 0.1)
				(type default)
			)
			(layer "B.Fab")
		)
		(fp_line
			(start 0.12065 0.2794)
			(end 0.12065 0.3048)
			(stroke
				(width 0.1)
				(type default)
			)
			(layer "B.Fab")
		)
		(fp_line
			(start 0.12065 -0.2794)
			(end -0.12065 -0.2794)
			(stroke
				(width 0.1)
				(type default)
			)
			(layer "B.Fab")
		)
		(fp_line
			(start 0.12065 -0.305054)
			(end 0.12065 -0.2794)
			(stroke
				(width 0.1)
				(type default)
			)
			(layer "B.Fab")
		)
		(fp_line
			(start -0.120396 0.3048)
			(end -0.120396 0.2794)
			(stroke
				(width 0.1)
				(type default)
			)
			(layer "B.Fab")
		)
		(fp_line
			(start -0.120396 0.2794)
			(end 0.12065 0.2794)
			(stroke
				(width 0.1)
				(type default)
			)
			(layer "B.Fab")
		)
		(fp_line
			(start -0.12065 -0.2794)
			(end -0.12065 -0.3048)
			(stroke
				(width 0.1)
				(type default)
			)
			(layer "B.Fab")
		)
		(fp_line
			(start -0.12065 -0.3048)
			(end -0.67945 -0.3048)
			(stroke
				(width 0.1)
				(type default)
			)
			(layer "B.Fab")
		)
		(fp_line
			(start -0.67945 0.3048)
			(end -0.120396 0.3048)
			(stroke
				(width 0.1)
				(type default)
			)
			(layer "B.Fab")
		)
		(fp_line
			(start -0.67945 -0.3048)
			(end -0.67945 0.3048)
			(stroke
				(width 0.1)
				(type default)
			)
			(layer "B.Fab")
		)
		(pad "1" smd circle
			(at 0.40005 0)
			(size 0 0)
			(layers "B.Cu" "B.Mask" "B.Paste")
			(net "SMB_P52V_VPDB_SCL")
		)
		(pad "2" smd circle
			(at -0.40005 0)
			(size 0 0)
			(layers "B.Cu" "B.Mask" "B.Paste")
			(net "SMB_BRICK3_SCL")
		)
	)
)
